(kicad_pcb
	(version 20260206)
	(generator "pcbnew")
	(generator_version "10.0")
	(general
		(thickness 1.6)
		(legacy_teardrops no)
	)
	(paper "A4")
	(title_block
		(title "03242023_DA0F0TMBIJ0_F0T_Motherboard_J_brd_V01_OCP.brd")
		(comment 1 "Grand Teton / footprint 1682 of 6105 (U1), pads 4436-4541 of 4677")
	)
	(layers
		(0 "F.Cu" signal "TOP")
		(4 "In1.Cu" signal "GND")
		(6 "In2.Cu" signal "IN1")
		(8 "In3.Cu" signal "GND1")
		(10 "In4.Cu" signal "IN2")
		(12 "In5.Cu" signal "GND2")
		(14 "In6.Cu" signal "IN3")
		(16 "In7.Cu" signal "GND3")
		(18 "In8.Cu" signal "VCC")
		(20 "In9.Cu" signal "VCC1")
		(22 "In10.Cu" signal "GND4")
		(24 "In11.Cu" signal "IN4")
		(26 "In12.Cu" signal "GND5")
		(28 "In13.Cu" signal "IN5")
		(30 "In14.Cu" signal "GND6")
		(32 "In15.Cu" signal "IN6")
		(34 "In16.Cu" signal "GND7")
		(2 "B.Cu" signal "BOTTOM")
		(9 "F.Adhes" user "F.Adhesive")
		(11 "B.Adhes" user "B.Adhesive")
		(13 "F.Paste" user "Package Geometry/Pastemask Top")
		(15 "B.Paste" user "Package Geometry/Pastemask Bottom")
		(5 "F.SilkS" user "Ref Des/Silkscreen Top")
		(7 "B.SilkS" user "Ref Des/Silkscreen Bottom")
		(1 "F.Mask" user "Board Geometry/Soldermask Top")
		(3 "B.Mask" user "Board Geometry/Soldermask Bottom")
		(17 "Dwgs.User" user "User.Drawings")
		(19 "Cmts.User" user "User.Comments")
		(21 "Eco1.User" user "User.Eco1")
		(23 "Eco2.User" user "User.Eco2")
		(25 "Edge.Cuts" user "Board Geometry/Outline")
		(27 "Margin" user)
		(31 "F.CrtYd" user "Package Geometry/Place Bound Top")
		(29 "B.CrtYd" user "Package Geometry/Place Bound Bottom")
		(35 "F.Fab" user "Ref Des/Assembly Top")
		(33 "B.Fab" user "Ref Des/Assembly Bottom")
	)
	(footprint ""
		(layer "F.Cu")
		(at 111.93018 -251.76988 90)
		(property "Reference" "U1"
			(at -74.913236 41.548812 0)
			(unlocked yes)
			(layer "F.SilkS")
			(effects
				(font
					(size 1.6002 1.1938)
					(thickness 0.1524)
				)
				(justify left)
			)
		)
		(property "Value" ""
			(at 0 0 90)
			(layer "F.Fab")
			(effects
				(font
					(size 1.27 1.27)
				)
			)
		)
		(duplicate_pad_numbers_are_jumpers no)
		(pad "R58" smd circle
			(at 10.566654 -20.385532 270)
			(size 0.4318 0.4318)
			(layers "F.Cu" "F.Mask" "F.Paste")
			(net "M_B_CPU1_SA_DQS_DN<3>")
		)
		(pad "R60" smd circle
			(at 12.19454 -20.385532 270)
			(size 0.4318 0.4318)
			(layers "F.Cu" "F.Mask" "F.Paste")
			(net "GND")
		)
		(pad "R62" smd circle
			(at 13.822426 -20.385532 270)
			(size 0.4318 0.4318)
			(layers "F.Cu" "F.Mask" "F.Paste")
			(net "GND")
		)
		(pad "R64" smd circle
			(at 15.450058 -20.385532 270)
			(size 0.4318 0.4318)
			(layers "F.Cu" "F.Mask" "F.Paste")
			(net "M_C_CPU1_SA_DQS_DN<2>")
		)
		(pad "R66" smd circle
			(at 17.07769 -20.385532 270)
			(size 0.4318 0.4318)
			(layers "F.Cu" "F.Mask" "F.Paste")
			(net "GND")
		)
		(pad "R68" smd circle
			(at 18.705576 -20.385532 270)
			(size 0.4318 0.4318)
			(layers "F.Cu" "F.Mask" "F.Paste")
			(net "GND")
		)
		(pad "R70" smd circle
			(at 20.333462 -20.385532 270)
			(size 0.4318 0.4318)
			(layers "F.Cu" "F.Mask" "F.Paste")
			(net "M_B_CPU1_SA_DQS_DN<1>")
		)
		(pad "R72" smd circle
			(at 21.961094 -20.385532 270)
			(size 0.4318 0.4318)
			(layers "F.Cu" "F.Mask" "F.Paste")
			(net "GND")
		)
		(pad "R74" smd circle
			(at 23.58898 -20.385532 270)
			(size 0.4318 0.4318)
			(layers "F.Cu" "F.Mask" "F.Paste")
			(net "GND")
		)
		(pad "R76" smd circle
			(at 25.216612 -20.385532 270)
			(size 0.4318 0.4318)
			(layers "F.Cu" "F.Mask" "F.Paste")
			(net "M_C_CPU1_SA_DQS_DN<0>")
		)
		(pad "R78" smd circle
			(at 26.844498 -20.385532 270)
			(size 0.4318 0.4318)
			(layers "F.Cu" "F.Mask" "F.Paste")
			(net "GND")
		)
		(pad "R80" smd circle
			(at 28.472384 -20.385532 270)
			(size 0.4318 0.4318)
			(layers "F.Cu" "F.Mask" "F.Paste")
			(net "PVCCFA_EHV_FIVRA_CPU1")
		)
		(pad "R82" smd circle
			(at 30.100016 -20.385532 270)
			(size 0.4318 0.4318)
			(layers "F.Cu" "F.Mask" "F.Paste")
			(net "UPI_CPU1_CPU0_P2P2_DN<6>")
		)
		(pad "R84" smd circle
			(at 31.727902 -20.385532 270)
			(size 0.4318 0.4318)
			(layers "F.Cu" "F.Mask" "F.Paste")
			(net "GND")
		)
		(pad "R86" smd circle
			(at 33.355534 -20.385532 270)
			(size 0.4318 0.4318)
			(layers "F.Cu" "F.Mask" "F.Paste")
			(net "P5E_CPU1_PE4_TX_DN<2>")
		)
		(pad "R88" smd circle
			(at 34.98342 -20.385532 270)
			(size 0.4318 0.4318)
			(layers "F.Cu" "F.Mask" "F.Paste")
			(net "GND")
		)
		(pad "R90" smd circle
			(at 36.611306 -20.385532 270)
			(size 0.4318 0.4318)
			(layers "F.Cu" "F.Mask" "F.Paste")
			(net "P5E_CPU1_PE4_RX_DP<2>")
		)
		(pad "T2" smd circle
			(at -36.611306 -20.025868 270)
			(size 0.4318 0.4318)
			(layers "F.Cu" "F.Mask" "F.Paste")
			(net "UPI_CPU1_CPU0_P0P1_DN<3>")
		)
		(pad "T4" smd circle
			(at -34.98342 -20.025868 270)
			(size 0.4318 0.4318)
			(layers "F.Cu" "F.Mask" "F.Paste")
			(net "GND")
		)
		(pad "T6" smd circle
			(at -33.355534 -20.025868 270)
			(size 0.4318 0.4318)
			(layers "F.Cu" "F.Mask" "F.Paste")
			(net "UPI_CPU0_CPU1_P1P0_DP<3>")
		)
		(pad "T8" smd circle
			(at -31.727902 -20.025868 270)
			(size 0.4318 0.4318)
			(layers "F.Cu" "F.Mask" "F.Paste")
			(net "GND")
		)
		(pad "T10" smd circle
			(at -30.100016 -20.025868 270)
			(size 0.4318 0.4318)
			(layers "F.Cu" "F.Mask" "F.Paste")
			(net "P5E_CPU1_PE0_RX_DN<3>")
		)
		(pad "T12" smd circle
			(at -28.472384 -20.025868 270)
			(size 0.4318 0.4318)
			(layers "F.Cu" "F.Mask" "F.Paste")
			(net "GND")
		)
		(pad "T14" smd circle
			(at -26.844498 -20.025868 270)
			(size 0.4318 0.4318)
			(layers "F.Cu" "F.Mask" "F.Paste")
			(net "P5E_CPU1_PE0_TX_DP<2>")
		)
		(pad "T16" smd circle
			(at -25.216612 -20.025868 270)
			(size 0.4318 0.4318)
			(layers "F.Cu" "F.Mask" "F.Paste")
			(net "GND")
		)
		(pad "T18" smd circle
			(at -23.58898 -20.025868 270)
			(size 0.4318 0.4318)
			(layers "F.Cu" "F.Mask" "F.Paste")
			(net "GND")
		)
		(pad "T20" smd circle
			(at -21.961094 -20.025868 270)
			(size 0.4318 0.4318)
			(layers "F.Cu" "F.Mask" "F.Paste")
			(net "M_C_CPU1_SB_DQ<20>")
		)
		(pad "T22" smd circle
			(at -20.333462 -20.025868 270)
			(size 0.4318 0.4318)
			(layers "F.Cu" "F.Mask" "F.Paste")
			(net "M_C_CPU1_SB_DQ<17>")
		)
		(pad "T24" smd circle
			(at -18.705576 -20.025868 270)
			(size 0.4318 0.4318)
			(layers "F.Cu" "F.Mask" "F.Paste")
			(net "GND")
		)
		(pad "T26" smd circle
			(at -17.07769 -20.025868 270)
			(size 0.4318 0.4318)
			(layers "F.Cu" "F.Mask" "F.Paste")
			(net "M_B_CPU1_SB_DQ<4>")
		)
		(pad "T28" smd circle
			(at -15.450058 -20.025868 270)
			(size 0.4318 0.4318)
			(layers "F.Cu" "F.Mask" "F.Paste")
			(net "M_B_CPU1_SB_DQ<1>")
		)
		(pad "T30" smd circle
			(at -13.822426 -20.025868 270)
			(size 0.4318 0.4318)
			(layers "F.Cu" "F.Mask" "F.Paste")
			(net "GND")
		)
		(pad "T32" smd circle
			(at -12.19454 -20.025868 270)
			(size 0.4318 0.4318)
			(layers "F.Cu" "F.Mask" "F.Paste")
			(net "M_C_CPU1_SB_CB<0>")
		)
		(pad "T34" smd circle
			(at -10.566654 -20.025868 270)
			(size 0.4318 0.4318)
			(layers "F.Cu" "F.Mask" "F.Paste")
			(net "M_C_CPU1_SB_CB<5>")
		)
		(pad "T36" smd circle
			(at -8.939022 -20.025868 270)
			(size 0.4318 0.4318)
			(layers "F.Cu" "F.Mask" "F.Paste")
			(net "GND")
		)
		(pad "T38" smd circle
			(at -7.311136 -20.025868 270)
			(size 0.4318 0.4318)
			(layers "F.Cu" "F.Mask" "F.Paste")
			(net "M_C_CPU1_SB_CS_N<0>")
		)
		(pad "T40" smd circle
			(at -5.68325 -20.025868 270)
			(size 0.4318 0.4318)
			(layers "F.Cu" "F.Mask" "F.Paste")
			(net "M_C_CPU1_SB_CA<4>")
		)
		(pad "T42" smd circle
			(at -4.055618 -20.025868 270)
			(size 0.4318 0.4318)
			(layers "F.Cu" "F.Mask" "F.Paste")
			(net "GND")
		)
		(pad "T44" smd circle
			(at -2.427732 -20.025868 270)
			(size 0.4318 0.4318)
			(layers "F.Cu" "F.Mask" "F.Paste")
			(net "M_B_CPU1_SB_CA<0>")
		)
		(pad "T47" smd circle
			(at 1.613916 -19.915886 270)
			(size 0.4318 0.4318)
			(layers "F.Cu" "F.Mask" "F.Paste")
			(net "M_C_CPU1_SA_PAR")
		)
		(pad "T49" smd circle
			(at 3.241802 -19.915886 270)
			(size 0.4318 0.4318)
			(layers "F.Cu" "F.Mask" "F.Paste")
			(net "GND")
		)
		(pad "T51" smd circle
			(at 4.869434 -19.915886 270)
			(size 0.4318 0.4318)
			(layers "F.Cu" "F.Mask" "F.Paste")
			(net "M_C_CPU1_SA_CA<2>")
		)
		(pad "T53" smd circle
			(at 6.49732 -19.915886 270)
			(size 0.4318 0.4318)
			(layers "F.Cu" "F.Mask" "F.Paste")
			(net "M_C_CPU1_SA_CS_N<1>")
		)
		(pad "T55" smd circle
			(at 8.124952 -19.915886 270)
			(size 0.4318 0.4318)
			(layers "F.Cu" "F.Mask" "F.Paste")
			(net "GND")
		)
		(pad "T57" smd circle
			(at 9.752838 -19.915886 270)
			(size 0.4318 0.4318)
			(layers "F.Cu" "F.Mask" "F.Paste")
			(net "M_B_CPU1_SA_DQ<28>")
		)
		(pad "T59" smd circle
			(at 11.380724 -19.915886 270)
			(size 0.4318 0.4318)
			(layers "F.Cu" "F.Mask" "F.Paste")
			(net "M_B_CPU1_SA_DQ<25>")
		)
		(pad "T61" smd circle
			(at 13.008356 -19.915886 270)
			(size 0.4318 0.4318)
			(layers "F.Cu" "F.Mask" "F.Paste")
			(net "GND")
		)
		(pad "T63" smd circle
			(at 14.635988 -19.915886 270)
			(size 0.4318 0.4318)
			(layers "F.Cu" "F.Mask" "F.Paste")
			(net "M_C_CPU1_SA_DQ<20>")
		)
		(pad "T65" smd circle
			(at 16.263874 -19.915886 270)
			(size 0.4318 0.4318)
			(layers "F.Cu" "F.Mask" "F.Paste")
			(net "M_C_CPU1_SA_DQ<17>")
		)
		(pad "T67" smd circle
			(at 17.89176 -19.915886 270)
			(size 0.4318 0.4318)
			(layers "F.Cu" "F.Mask" "F.Paste")
			(net "GND")
		)
		(pad "T69" smd circle
			(at 19.519392 -19.915886 270)
			(size 0.4318 0.4318)
			(layers "F.Cu" "F.Mask" "F.Paste")
			(net "M_B_CPU1_SA_DQ<12>")
		)
		(pad "T71" smd circle
			(at 21.147278 -19.915886 270)
			(size 0.4318 0.4318)
			(layers "F.Cu" "F.Mask" "F.Paste")
			(net "M_B_CPU1_SA_DQ<9>")
		)
		(pad "T73" smd circle
			(at 22.77491 -19.915886 270)
			(size 0.4318 0.4318)
			(layers "F.Cu" "F.Mask" "F.Paste")
			(net "GND")
		)
		(pad "T75" smd circle
			(at 24.402796 -19.915886 270)
			(size 0.4318 0.4318)
			(layers "F.Cu" "F.Mask" "F.Paste")
			(net "M_C_CPU1_SA_DQ<4>")
		)
		(pad "T77" smd circle
			(at 26.030682 -19.915886 270)
			(size 0.4318 0.4318)
			(layers "F.Cu" "F.Mask" "F.Paste")
			(net "M_C_CPU1_SA_DQ<1>")
		)
		(pad "T79" smd circle
			(at 27.658314 -19.915886 270)
			(size 0.4318 0.4318)
			(layers "F.Cu" "F.Mask" "F.Paste")
			(net "GND")
		)
		(pad "T81" smd circle
			(at 29.2862 -19.915886 270)
			(size 0.4318 0.4318)
			(layers "F.Cu" "F.Mask" "F.Paste")
			(net "UPI_CPU1_CPU0_P2P2_DP<5>")
		)
		(pad "T83" smd circle
			(at 30.914086 -19.915886 270)
			(size 0.4318 0.4318)
			(layers "F.Cu" "F.Mask" "F.Paste")
			(net "GND")
		)
		(pad "T85" smd circle
			(at 32.541718 -19.915886 270)
			(size 0.4318 0.4318)
			(layers "F.Cu" "F.Mask" "F.Paste")
			(net "PVCCFA_EHV_FIVRA_CPU1")
		)
		(pad "T87" smd circle
			(at 34.169604 -19.915886 270)
			(size 0.4318 0.4318)
			(layers "F.Cu" "F.Mask" "F.Paste")
			(net "P5E_CPU1_PE4_TX_DP<2>")
		)
		(pad "T89" smd circle
			(at 35.797236 -19.915886 270)
			(size 0.4318 0.4318)
			(layers "F.Cu" "F.Mask" "F.Paste")
			(net "PVCCFA_EHV_FIVRA_CPU1")
		)
		(pad "T91" smd oval
			(at 37.425122 -19.915886)
			(size 0.381 0.4826)
			(drill
				(offset 0 -0.0508)
			)
			(layers "F.Cu" "F.Mask" "F.Paste")
			(net "P5E_CPU1_PE4_RX_DN<2>")
		)
		(pad "U1" smd oval
			(at -37.425122 -19.555714 180)
			(size 0.381 0.4826)
			(drill
				(offset 0 -0.0508)
			)
			(layers "F.Cu" "F.Mask" "F.Paste")
			(net "UPI_CPU1_CPU0_P0P1_DN<4>")
		)
		(pad "U3" smd circle
			(at -35.797236 -19.555714 270)
			(size 0.4318 0.4318)
			(layers "F.Cu" "F.Mask" "F.Paste")
			(net "PVCCFA_EHV_CPU1")
		)
		(pad "U5" smd circle
			(at -34.169604 -19.555714 270)
			(size 0.4318 0.4318)
			(layers "F.Cu" "F.Mask" "F.Paste")
			(net "UPI_CPU0_CPU1_P1P0_DN<3>")
		)
		(pad "U7" smd circle
			(at -32.541718 -19.555714 270)
			(size 0.4318 0.4318)
			(layers "F.Cu" "F.Mask" "F.Paste")
			(net "PVCCFA_EHV_FIVRA_CPU1")
		)
		(pad "U9" smd circle
			(at -30.914086 -19.555714 270)
			(size 0.4318 0.4318)
			(layers "F.Cu" "F.Mask" "F.Paste")
			(net "P5E_CPU1_PE0_RX_DP<3>")
		)
		(pad "U11" smd circle
			(at -29.2862 -19.555714 270)
			(size 0.4318 0.4318)
			(layers "F.Cu" "F.Mask" "F.Paste")
			(net "PVCCFA_EHV_FIVRA_CPU1")
		)
		(pad "U13" smd circle
			(at -27.658314 -19.555714 270)
			(size 0.4318 0.4318)
			(layers "F.Cu" "F.Mask" "F.Paste")
			(net "P5E_CPU1_PE0_TX_DN<2>")
		)
		(pad "U15" smd circle
			(at -26.030682 -19.555714 270)
			(size 0.4318 0.4318)
			(layers "F.Cu" "F.Mask" "F.Paste")
			(net "PVCCFA_EHV_FIVRA_CPU1")
		)
		(pad "U17" smd circle
			(at -24.402796 -19.555714 270)
			(size 0.4318 0.4318)
			(layers "F.Cu" "F.Mask" "F.Paste")
			(net "NC_CPU1_HBM0_VIEWDIG0")
		)
		(pad "U19" smd circle
			(at -22.77491 -19.555714 270)
			(size 0.4318 0.4318)
			(layers "F.Cu" "F.Mask" "F.Paste")
			(net "M_C_CPU1_SB_DQ<21>")
		)
		(pad "U21" smd circle
			(at -21.147278 -19.555714 270)
			(size 0.4318 0.4318)
			(layers "F.Cu" "F.Mask" "F.Paste")
			(net "M_C_CPU1_SB_DQS_DP<2>")
		)
		(pad "U23" smd circle
			(at -19.519392 -19.555714 270)
			(size 0.4318 0.4318)
			(layers "F.Cu" "F.Mask" "F.Paste")
			(net "M_C_CPU1_SB_DQ<16>")
		)
		(pad "U25" smd circle
			(at -17.89176 -19.555714 270)
			(size 0.4318 0.4318)
			(layers "F.Cu" "F.Mask" "F.Paste")
			(net "M_B_CPU1_SB_DQ<5>")
		)
		(pad "U27" smd circle
			(at -16.263874 -19.555714 270)
			(size 0.4318 0.4318)
			(layers "F.Cu" "F.Mask" "F.Paste")
			(net "M_B_CPU1_SB_DQS_DP<0>")
		)
		(pad "U29" smd circle
			(at -14.635988 -19.555714 270)
			(size 0.4318 0.4318)
			(layers "F.Cu" "F.Mask" "F.Paste")
			(net "M_B_CPU1_SB_DQ<0>")
		)
		(pad "U31" smd circle
			(at -13.008356 -19.555714 270)
			(size 0.4318 0.4318)
			(layers "F.Cu" "F.Mask" "F.Paste")
			(net "M_C_CPU1_SB_CB<1>")
		)
		(pad "U33" smd circle
			(at -11.380724 -19.555714 270)
			(size 0.4318 0.4318)
			(layers "F.Cu" "F.Mask" "F.Paste")
			(net "M_C_CPU1_SB_DQS_DP<9>")
		)
		(pad "U35" smd circle
			(at -9.752838 -19.555714 270)
			(size 0.4318 0.4318)
			(layers "F.Cu" "F.Mask" "F.Paste")
			(net "M_C_CPU1_SB_CB<4>")
		)
		(pad "U37" smd circle
			(at -8.124952 -19.555714 270)
			(size 0.4318 0.4318)
			(layers "F.Cu" "F.Mask" "F.Paste")
			(net "M_C_CPU1_SB_CS_N<1>")
		)
		(pad "U39" smd circle
			(at -6.49732 -19.555714 270)
			(size 0.4318 0.4318)
			(layers "F.Cu" "F.Mask" "F.Paste")
			(net "GND")
		)
		(pad "U41" smd circle
			(at -4.869434 -19.555714 270)
			(size 0.4318 0.4318)
			(layers "F.Cu" "F.Mask" "F.Paste")
			(net "M_C_CPU1_SB_CA<2>")
		)
		(pad "U43" smd circle
			(at -3.241802 -19.555714 270)
			(size 0.4318 0.4318)
			(layers "F.Cu" "F.Mask" "F.Paste")
			(net "M_B_CPU1_SB_CA<1>")
		)
		(pad "U45" smd circle
			(at -1.613916 -19.555714 270)
			(size 0.4318 0.4318)
			(layers "F.Cu" "F.Mask" "F.Paste")
			(net "M_B_CPU1_CLK_DP<0>")
		)
		(pad "U48" smd circle
			(at 2.427732 -19.445732 270)
			(size 0.4318 0.4318)
			(layers "F.Cu" "F.Mask" "F.Paste")
			(net "M_C_CPU1_SA_CA<6>")
		)
		(pad "U50" smd circle
			(at 4.055618 -19.445732 270)
			(size 0.4318 0.4318)
			(layers "F.Cu" "F.Mask" "F.Paste")
			(net "M_C_CPU1_SA_CA<4>")
		)
		(pad "U52" smd circle
			(at 5.68325 -19.445732 270)
			(size 0.4318 0.4318)
			(layers "F.Cu" "F.Mask" "F.Paste")
			(net "GND")
		)
		(pad "U54" smd circle
			(at 7.311136 -19.445732 270)
			(size 0.4318 0.4318)
			(layers "F.Cu" "F.Mask" "F.Paste")
			(net "M_C_CPU1_SA_CS_N<0>")
		)
		(pad "U56" smd circle
			(at 8.939022 -19.445732 270)
			(size 0.4318 0.4318)
			(layers "F.Cu" "F.Mask" "F.Paste")
			(net "M_B_CPU1_SA_DQ<29>")
		)
		(pad "U58" smd circle
			(at 10.566654 -19.445732 270)
			(size 0.4318 0.4318)
			(layers "F.Cu" "F.Mask" "F.Paste")
			(net "M_B_CPU1_SA_DQS_DP<3>")
		)
		(pad "U60" smd circle
			(at 12.19454 -19.445732 270)
			(size 0.4318 0.4318)
			(layers "F.Cu" "F.Mask" "F.Paste")
			(net "M_B_CPU1_SA_DQ<24>")
		)
		(pad "U62" smd circle
			(at 13.822426 -19.445732 270)
			(size 0.4318 0.4318)
			(layers "F.Cu" "F.Mask" "F.Paste")
			(net "M_C_CPU1_SA_DQ<21>")
		)
		(pad "U64" smd circle
			(at 15.450058 -19.445732 270)
			(size 0.4318 0.4318)
			(layers "F.Cu" "F.Mask" "F.Paste")
			(net "M_C_CPU1_SA_DQS_DP<2>")
		)
		(pad "U66" smd circle
			(at 17.07769 -19.445732 270)
			(size 0.4318 0.4318)
			(layers "F.Cu" "F.Mask" "F.Paste")
			(net "M_C_CPU1_SA_DQ<16>")
		)
		(pad "U68" smd circle
			(at 18.705576 -19.445732 270)
			(size 0.4318 0.4318)
			(layers "F.Cu" "F.Mask" "F.Paste")
			(net "M_B_CPU1_SA_DQ<13>")
		)
		(pad "U70" smd circle
			(at 20.333462 -19.445732 270)
			(size 0.4318 0.4318)
			(layers "F.Cu" "F.Mask" "F.Paste")
			(net "M_B_CPU1_SA_DQS_DP<1>")
		)
		(pad "U72" smd circle
			(at 21.961094 -19.445732 270)
			(size 0.4318 0.4318)
			(layers "F.Cu" "F.Mask" "F.Paste")
			(net "M_B_CPU1_SA_DQ<8>")
		)
		(pad "U74" smd circle
			(at 23.58898 -19.445732 270)
			(size 0.4318 0.4318)
			(layers "F.Cu" "F.Mask" "F.Paste")
			(net "M_C_CPU1_SA_DQ<5>")
		)
		(pad "U76" smd circle
			(at 25.216612 -19.445732 270)
			(size 0.4318 0.4318)
			(layers "F.Cu" "F.Mask" "F.Paste")
			(net "M_C_CPU1_SA_DQS_DP<0>")
		)
		(pad "U78" smd circle
			(at 26.844498 -19.445732 270)
			(size 0.4318 0.4318)
			(layers "F.Cu" "F.Mask" "F.Paste")
			(net "M_C_CPU1_SA_DQ<0>")
		)
		(pad "U80" smd circle
			(at 28.472384 -19.445732 270)
			(size 0.4318 0.4318)
			(layers "F.Cu" "F.Mask" "F.Paste")
			(net "UPI_CPU1_CPU0_P2P2_DN<7>")
		)
		(pad "U82" smd circle
			(at 30.100016 -19.445732 270)
			(size 0.4318 0.4318)
			(layers "F.Cu" "F.Mask" "F.Paste")
			(net "GND")
		)
		(pad "U84" smd circle
			(at 31.727902 -19.445732 270)
			(size 0.4318 0.4318)
			(layers "F.Cu" "F.Mask" "F.Paste")
			(net "GND")
		)
		(pad "U86" smd circle
			(at 33.355534 -19.445732 270)
			(size 0.4318 0.4318)
			(layers "F.Cu" "F.Mask" "F.Paste")
			(net "P5E_CPU1_PE4_TX_DN<3>")
		)
		(pad "U88" smd circle
			(at 34.98342 -19.445732 270)
			(size 0.4318 0.4318)
			(layers "F.Cu" "F.Mask" "F.Paste")
			(net "GND")
		)
	)
)
